#ISCELL
  logical_power bom_note *
  *
#ISCELL
  mstr_misc dns *
  *
#ISCELL
  pure_quanta quanta_title_block_c *
  *
#ISCELL
  standard gnd_power *
  page57_i1
#CELL
  pure_quanta hole *
  page57_i14
#ISCELL
  standard gnd_power *
  page57_i31
#ISCELL
  standard gnd_power *
  page57_i33
#CELL
  pure_quanta hole *
  page57_i34
#CELL
  pure_quanta hole *
  page57_i35
#CELL
  pure_quanta hole *
  page57_i36
#ISCELL
  standard gnd_power *
  page57_i37
#CELL
  pure_quanta hole *
  page57_i38
#ISCELL
  standard gnd_power *
  page57_i39
#CELL
  pure_quanta hole *
  page57_i40
#ISCELL
  standard gnd_power *
  page57_i41
#ISCELL
  standard gnd_power *
  page57_i43
#CELL
  pure_quanta hole *
  page57_i45
#CELL
  pure_quanta hole *
  page57_i49
#CELL
  pure_quanta hole *
  page57_i50
#CELL
  pure_quanta hole *
  page57_i51
